# S9S_MB_2U (Grand Teton) — schematic parts with pin connectivity, parts 1626–1627 of 6093; source: Cadence DE-HDL packaged netlist (pstxprt.dat, pstxnet.dat, pstchip.dat)

J35  SCONN168_ME1016810202011  IO  pkg CON_F168S2H7D_P0-6W2-95_LUH  page 159
  A1  GND_A1  POWER  = GND
  A2  GND_A2  POWER  = GND
  A3  GND_A3  POWER  = GND
  A4  GND_A4  POWER  = GND
  A5  GND_A5  POWER  = GND
  A6  GND_A6  POWER  = GND
  A7  SMCLK  OUT  = SMB_OCP_V3_2_3V3AUX_BUF_R_SCL
  A8  SMDAT  BI  = SMB_OCP_V3_2_3V3AUX_BUF_R_SDA
  A9  \smrst#\  OUT  = RST_SMB_OCP_V3_2_N
  A10  \prsnta#\  OUT  = OCP_V3_1_PRSNTA_R_N
  A11  \perst1#\  OUT  = RST_PERST1_OCP_V3_2_N
  A12  \prsntb2#\  IN  = OCP_V3_2_PRSNT2_R_N
  A13  GND_A13  POWER  = GND
  A14  REFCLKN1  OUT  = CLK_100M_OCP_V3_2_B_DN
  A15  REFCLKP1  OUT  = CLK_100M_OCP_V3_2_B_DP
  A16  GND_A16  POWER  = GND
  A17  PERN0  IN  = P5E_CPU1_PE1_RX_DN<0>
  A18  PERP0  IN  = P5E_CPU1_PE1_RX_DP<0>
  A19  GND_A19  POWER  = GND
  A20  PERN1  IN  = P5E_CPU1_PE1_RX_DN<1>
  A21  PERP1  IN  = P5E_CPU1_PE1_RX_DP<1>
  A22  GND_A22  POWER  = GND
  A23  PERN2  IN  = P5E_CPU1_PE1_RX_DN<2>
  A24  PERP2  IN  = P5E_CPU1_PE1_RX_DP<2>
  A25  GND_A25  POWER  = GND
  A26  PERN3  IN  = P5E_CPU1_PE1_RX_DN<3>
  A27  PERP3  IN  = P5E_CPU1_PE1_RX_DP<3>
  A28  GND_A28  POWER  = GND
  A29  GND_A29  POWER  = GND
  A30  PERN4  IN  = P5E_CPU1_PE1_RX_DN<4>
  A31  PERP4  IN  = P5E_CPU1_PE1_RX_DP<4>
  A32  GND_A32  POWER  = GND
  A33  PERN5  IN  = P5E_CPU1_PE1_RX_DN<5>
  A34  PERP5  IN  = P5E_CPU1_PE1_RX_DP<5>
  A35  GND_A35  POWER  = GND
  A36  PERN6  IN  = P5E_CPU1_PE1_RX_DN<6>
  A37  PERP6  IN  = P5E_CPU1_PE1_RX_DP<6>
  A38  GND_A38  POWER  = GND
  A39  PERN7  IN  = P5E_CPU1_PE1_RX_DN<7>
  A40  PERP7  IN  = P5E_CPU1_PE1_RX_DP<7>
  A41  GND_A41  POWER  = GND
  A42  \prsntb1#\  IN  = OCP_V3_2_PRSNT1_R_N
  A43  GND_A43  POWER  = GND
  A44  PERN8  IN  = P5E_CPU1_PE1_RX_DN<8>
  A45  PERP8  IN  = P5E_CPU1_PE1_RX_DP<8>
  A46  GND_A46  POWER  = GND
  A47  PERN9  IN  = P5E_CPU1_PE1_RX_DN<9>
  A48  PERP9  IN  = P5E_CPU1_PE1_RX_DP<9>
  A49  GND_A49  POWER  = GND
  A50  PERN10  IN  = P5E_CPU1_PE1_RX_DN<10>
  A51  PERP10  IN  = P5E_CPU1_PE1_RX_DP<10>
  A52  GND_A52  POWER  = GND
  A53  PERN11  IN  = P5E_CPU1_PE1_RX_DN<11>
  A54  PERP11  IN  = P5E_CPU1_PE1_RX_DP<11>
  A55  GND_A55  POWER  = GND
  A56  PERN12  IN  = P5E_CPU1_PE1_RX_DN<12>
  A57  PERP12  IN  = P5E_CPU1_PE1_RX_DP<12>
  A58  GND_A58  POWER  = GND
  A59  PERN13  IN  = P5E_CPU1_PE1_RX_DN<13>
  A60  PERP13  IN  = P5E_CPU1_PE1_RX_DP<13>
  A61  GND_A61  POWER  = GND
  A62  PERN14  IN  = P5E_CPU1_PE1_RX_DN<14>
  A63  PERP14  IN  = P5E_CPU1_PE1_RX_DP<14>
  A64  GND_A64  POWER  = GND
  A65  PERN15  IN  = P5E_CPU1_PE1_RX_DN<15>
  A66  PERP15  IN  = P5E_CPU1_PE1_RX_DP<15>
  A67  GND_A67  POWER  = GND
  A68  USB_DATN  BI  = USB2_5_R1_DN
  A69  USB_DATP  BI  = USB2_5_R1_DP
  A70  \pwrbrk0#\  BI  = OCP_V3_2_PWRBRK_N
  B1  \+12v_edge_b1\  POWER  = P12V_OCP_V3_2
  B2  \+12v_edge_b2\  POWER  = P12V_OCP_V3_2
  B3  \+12v_edge_b3\  POWER  = P12V_OCP_V3_2
  B4  \+12v_edge_b4\  POWER  = P12V_OCP_V3_2
  B5  \+12v_edge_b5\  POWER  = P12V_OCP_V3_2
  B6  \+12v_edge_b6\  POWER  = P12V_OCP_V3_2
  B7  \bif0#\  OUT  = OCP_V3_2_BIF0_R_N
  B8  \bif1#\  OUT  = OCP_V3_2_BIF1_R_N
  B9  \bif2#\  OUT  = OCP_V3_2_BIF2_R_N
  B10  \perst0#\  OUT  = RST_PERST0_OCP_V3_2_N
  B11  \+3.3v_edge\  POWER  = P3V3_OCP_V3_2
  B12  AUX_PWR_EN  OUT  = OCP_V3_2_AUX_PWR_EN_R
  B13  GND_B13  POWER  = GND
  B14  REFCLKN0  IN  = CLK_100M_OCP_V3_2_A_DN
  B15  REFCLKP0  OUT  = CLK_100M_OCP_V3_2_A_DP
  B16  GND_B16  POWER  = GND
  B17  PETN0  OUT  = P5E_CPU1_PE1_TX_C_DP<0>
  B18  PETP0  OUT  = P5E_CPU1_PE1_TX_C_DN<0>
  B19  GND_B19  POWER  = GND
  B20  PETN1  OUT  = P5E_CPU1_PE1_TX_C_DN<1>
  B21  PETP1  OUT  = P5E_CPU1_PE1_TX_C_DP<1>
  B22  GND_B22  POWER  = GND
  B23  PETN2  OUT  = P5E_CPU1_PE1_TX_C_DP<2>
  B24  PETP2  OUT  = P5E_CPU1_PE1_TX_C_DN<2>
  B25  GND_B25  POWER  = GND
  B26  PETN3  OUT  = P5E_CPU1_PE1_TX_C_DN<3>
  B27  PETP3  OUT  = P5E_CPU1_PE1_TX_C_DP<3>
  B28  GND_B28  POWER  = GND
  B29  GND_B29  POWER  = GND
  B30  PETN4  OUT  = P5E_CPU1_PE1_TX_C_DP<4>
  B31  PETP4  OUT  = P5E_CPU1_PE1_TX_C_DN<4>
  B32  GND_B32  POWER  = GND
  B33  PETN5  OUT  = P5E_CPU1_PE1_TX_C_DN<5>
  B34  PETP5  OUT  = P5E_CPU1_PE1_TX_C_DP<5>
  B35  GND_B35  POWER  = GND
  B36  PETN6  OUT  = P5E_CPU1_PE1_TX_C_DP<6>
  B37  PETP6  OUT  = P5E_CPU1_PE1_TX_C_DN<6>
  B38  GND_B38  POWER  = GND
  B39  PETN7  OUT  = P5E_CPU1_PE1_TX_C_DN<7>
  B40  PETP7  OUT  = P5E_CPU1_PE1_TX_C_DP<7>
  B41  GND_B41  POWER  = GND
  B42  \prsntb0#\  IN  = OCP_V3_2_PRSNT0_R_N
  B43  GND_B43  POWER  = GND
  B44  PETN8  OUT  = P5E_CPU1_PE1_TX_C_DP<8>
  B45  PETP8  OUT  = P5E_CPU1_PE1_TX_C_DN<8>
  B46  GND_B46  POWER  = GND
  B47  PETN9  OUT  = P5E_CPU1_PE1_TX_C_DN<9>
  B48  PETP9  OUT  = P5E_CPU1_PE1_TX_C_DP<9>
  B49  GND_B49  POWER  = GND
  B50  PETN10  OUT  = P5E_CPU1_PE1_TX_C_DP<10>
  B51  PETP10  OUT  = P5E_CPU1_PE1_TX_C_DN<10>
  B52  GND_B52  POWER  = GND
  B53  PETN11  OUT  = P5E_CPU1_PE1_TX_C_DN<11>
  B54  PETP11  OUT  = P5E_CPU1_PE1_TX_C_DP<11>
  B55  GND_B55  POWER  = GND
  B56  PETN12  OUT  = P5E_CPU1_PE1_TX_C_DP<12>
  B57  PETP12  OUT  = P5E_CPU1_PE1_TX_C_DN<12>
  B58  GND_B58  POWER  = GND
  B59  PETN13  OUT  = P5E_CPU1_PE1_TX_C_DN<13>
  B60  PETP13  OUT  = P5E_CPU1_PE1_TX_C_DP<13>
  B61  GND_B61  POWER  = GND
  B62  PETN14  OUT  = P5E_CPU1_PE1_TX_C_DP<14>
  B63  PETP14  OUT  = P5E_CPU1_PE1_TX_C_DN<14>
  B64  GND_B64  POWER  = GND
  B65  PETN15  OUT  = P5E_CPU1_PE1_TX_C_DN<15>
  B66  PETP15  OUT  = P5E_CPU1_PE1_TX_C_DP<15>
  B67  GND_B67  POWER  = GND
  B68  RFU1_NC_B68  TRI  = TP_OCP_V3_2_B68
  B69  RFU1_NC_B69  TRI  = TP_OCP_V3_2_B69
  B70  \prsntb3#\  IN  = OCP_V3_2_PRSNT3_R_N
  G1  G1  POWER  = GND
  G2  G2  POWER  = GND
  G3  G3  POWER  = GND
  G4  G4  POWER  = GND
  G5  G5  POWER  = GND
  OA1  \perst2#\  OUT  = RST_PERST2_OCP_V3_2_N
  OA2  \perst3#\  OUT  = RST_PERST3_OCP_V3_2_N
  OA3  \wake#\  IN  = IRQ_LVC3_OCP_V3_2_WAKE_N
  OA4  RBT_ARB_IN  IN  = OCP_V3_2_ISO1_RBT_ARB_IN
  OA5  RBT_ARB_OUT  OUT  = OCP_V3_2_ISO2_RBT_ARB_OUT
  OA6  SLOT_ID1  OUT  = OCP_V3_2_ID1
  OA7  RBT_TX_EN  OUT  = NCSI_OCP_V3_2_TX_EN
  OA8  RBT_TXD1  OUT  = NCSI_OCP_V3_2_TXD1
  OA9  RBT_TXD0  OUT  = NCSI_OCP_V3_2_TXD0
  OA10  GND_OA10  POWER  = GND
  OA11  REFCLKN3  OUT  = CLK_100M_OCP_V3_2_D_DN
  OA12  REFCLKP3  OUT  = CLK_100M_OCP_V3_2_D_DP
  OA13  GND_OA13  POWER  = GND
  OA14  RBT_CLK_IN  OUT  = CLK_50M_NCSI_OCP_V3_2_ISO
  OB1  NIC_PWR_GOOD  IN  = FM_OCP_V3_2_PWR_GOOD
  OB2  MAIN_PWR_EN  OUT  = OCP_V3_2_MAIN_PWR_EN_R
  OB3  \ld#\  OUT  = SGPIO_OCP_V3_2_LD_N
  OB4  DATA_IN  IN  = SGPIO_OCP_V3_2_DATAIN
  OB5  DATA_OUT  OUT  = SGPIO_OCP_V3_2_DATAOUT
  OB6  CLK  OUT  = SGPIO_OCP_V3_2_CLK
  OB7  SLOT_ID0  OUT  = OCP_V3_2_ID0
  OB8  RBT_RXD1  IN  = NCSI_OCP_V3_2_RXD1
  OB9  RBT_RXD0  IN  = NCSI_OCP_V3_2_RXD0
  OB10  GND_OB10  POWER  = GND
  OB11  REFCLKN2  OUT  = CLK_100M_OCP_V3_2_C_DN
  OB12  REFCLKP2  OUT  = CLK_100M_OCP_V3_2_C_DP
  OB13  GND_OB13  POWER  = GND
  OB14  RBT_CRS_DV  OUT  = NCSI_OCP_V3_2_CRS_DV

J37  SCONN168_ME1016810202011  IO  pkg CON_F168S2H7D_P0-6W2-95_LUH  page 153
  A1  GND_A1  POWER  = GND
  A2  GND_A2  POWER  = GND
  A3  GND_A3  POWER  = GND
  A4  GND_A4  POWER  = GND
  A5  GND_A5  POWER  = GND
  A6  GND_A6  POWER  = GND
  A7  SMCLK  OUT  = SMB_OCP_SFF_3V3AUX_BUF_R_SCL
  A8  SMDAT  BI  = SMB_OCP_SFF_3V3AUX_BUF_R_SDA
  A9  \smrst#\  OUT  = RST_SMB_OCP_SFF_N
  A10  \prsnta#\  OUT  = OCP_SFF_PRSNTA_R_N
  A11  \perst1#\  OUT  = RST_PERST1_OCP_SFF_N
  A12  \prsntb2#\  IN  = OCP_SFF_PRSNT2_R_N
  A13  GND_A13  POWER  = GND
  A14  REFCLKN1  OUT  = CLK_100M_OCP_SFF_1_DN
  A15  REFCLKP1  OUT  = CLK_100M_OCP_SFF_1_DP
  A16  GND_A16  POWER  = GND
  A17  PERN0  IN  = P5E_CPU0_PE1_RX_DN<0>
  A18  PERP0  IN  = P5E_CPU0_PE1_RX_DP<0>
  A19  GND_A19  POWER  = GND
  A20  PERN1  IN  = P5E_CPU0_PE1_RX_DP<1>
  A21  PERP1  IN  = P5E_CPU0_PE1_RX_DN<1>
  A22  GND_A22  POWER  = GND
  A23  PERN2  IN  = P5E_CPU0_PE1_RX_DP<2>
  A24  PERP2  IN  = P5E_CPU0_PE1_RX_DN<2>
  A25  GND_A25  POWER  = GND
  A26  PERN3  IN  = P5E_CPU0_PE1_RX_DP<3>
  A27  PERP3  IN  = P5E_CPU0_PE1_RX_DN<3>
  A28  GND_A28  POWER  = GND
  A29  GND_A29  POWER  = GND
  A30  PERN4  IN  = P5E_CPU0_PE1_RX_DP<4>
  A31  PERP4  IN  = P5E_CPU0_PE1_RX_DN<4>
  A32  GND_A32  POWER  = GND
  A33  PERN5  IN  = P5E_CPU0_PE1_RX_DP<5>
  A34  PERP5  IN  = P5E_CPU0_PE1_RX_DN<5>
  A35  GND_A35  POWER  = GND
  A36  PERN6  IN  = P5E_CPU0_PE1_RX_DP<6>
  A37  PERP6  IN  = P5E_CPU0_PE1_RX_DN<6>
  A38  GND_A38  POWER  = GND
  A39  PERN7  IN  = P5E_CPU0_PE1_RX_DP<7>
  A40  PERP7  IN  = P5E_CPU0_PE1_RX_DN<7>
  A41  GND_A41  POWER  = GND
  A42  \prsntb1#\  IN  = OCP_SFF_PRSNT1_R_N
  A43  GND_A43  POWER  = GND
  A44  PERN8  IN  = P5E_CPU0_PE1_RX_DP<8>
  A45  PERP8  IN  = P5E_CPU0_PE1_RX_DN<8>
  A46  GND_A46  POWER  = GND
  A47  PERN9  IN  = P5E_CPU0_PE1_RX_DP<9>
  A48  PERP9  IN  = P5E_CPU0_PE1_RX_DN<9>
  A49  GND_A49  POWER  = GND
  A50  PERN10  IN  = P5E_CPU0_PE1_RX_DP<10>
  A51  PERP10  IN  = P5E_CPU0_PE1_RX_DN<10>
  A52  GND_A52  POWER  = GND
  A53  PERN11  IN  = P5E_CPU0_PE1_RX_DP<11>
  A54  PERP11  IN  = P5E_CPU0_PE1_RX_DN<11>
  A55  GND_A55  POWER  = GND
  A56  PERN12  IN  = P5E_CPU0_PE1_RX_DP<12>
  A57  PERP12  IN  = P5E_CPU0_PE1_RX_DN<12>
  A58  GND_A58  POWER  = GND
  A59  PERN13  IN  = P5E_CPU0_PE1_RX_DP<13>
  A60  PERP13  IN  = P5E_CPU0_PE1_RX_DN<13>
  A61  GND_A61  POWER  = GND
  A62  PERN14  IN  = P5E_CPU0_PE1_RX_DP<14>
  A63  PERP14  IN  = P5E_CPU0_PE1_RX_DN<14>
  A64  GND_A64  POWER  = GND
  A65  PERN15  IN  = P5E_CPU0_PE1_RX_DP<15>
  A66  PERP15  IN  = P5E_CPU0_PE1_RX_DN<15>
  A67  GND_A67  POWER  = GND
  A68  USB_DATN  BI  = OCP_SFF_USB2_3_DN
  A69  USB_DATP  BI  = OCP_SFF_USB2_3_DP
  A70  \pwrbrk0#\  BI  = OCP_SFF_PWRBRK_N
  B1  \+12v_edge_b1\  POWER  = P12V_OCP_SFF
  B2  \+12v_edge_b2\  POWER  = P12V_OCP_SFF
  B3  \+12v_edge_b3\  POWER  = P12V_OCP_SFF
  B4  \+12v_edge_b4\  POWER  = P12V_OCP_SFF
  B5  \+12v_edge_b5\  POWER  = P12V_OCP_SFF
  B6  \+12v_edge_b6\  POWER  = P12V_OCP_SFF
  B7  \bif0#\  OUT  = OCP_SFF_BIF0_R_N
  B8  \bif1#\  OUT  = OCP_SFF_BIF1_R_N
  B9  \bif2#\  OUT  = OCP_SFF_BIF2_R_N
  B10  \perst0#\  OUT  = RST_PERST0_OCP_SFF_N
  B11  \+3.3v_edge\  POWER  = P3V3_OCP_SFF
  B12  AUX_PWR_EN  OUT  = OCP_SFF_AUX_PWR_EN_R
  B13  GND_B13  POWER  = GND
  B14  REFCLKN0  IN  = CLK_100M_OCP_SFF_0_DN
  B15  REFCLKP0  OUT  = CLK_100M_OCP_SFF_0_DP
  B16  GND_B16  POWER  = GND
  B17  PETN0  OUT  = P5E_CPU0_PE1_TX_C_DN<0>
  B18  PETP0  OUT  = P5E_CPU0_PE1_TX_C_DP<0>
  B19  GND_B19  POWER  = GND
  B20  PETN1  OUT  = P5E_CPU0_PE1_TX_C_DN<1>
  B21  PETP1  OUT  = P5E_CPU0_PE1_TX_C_DP<1>
  B22  GND_B22  POWER  = GND
  B23  PETN2  OUT  = P5E_CPU0_PE1_TX_C_DP<2>
  B24  PETP2  OUT  = P5E_CPU0_PE1_TX_C_DN<2>
  B25  GND_B25  POWER  = GND
  B26  PETN3  OUT  = P5E_CPU0_PE1_TX_C_DN<3>
  B27  PETP3  OUT  = P5E_CPU0_PE1_TX_C_DP<3>
  B28  GND_B28  POWER  = GND
  B29  GND_B29  POWER  = GND
  B30  PETN4  OUT  = P5E_CPU0_PE1_TX_C_DP<4>
  B31  PETP4  OUT  = P5E_CPU0_PE1_TX_C_DN<4>
  B32  GND_B32  POWER  = GND
  B33  PETN5  OUT  = P5E_CPU0_PE1_TX_C_DN<5>
  B34  PETP5  OUT  = P5E_CPU0_PE1_TX_C_DP<5>
  B35  GND_B35  POWER  = GND
  B36  PETN6  OUT  = P5E_CPU0_PE1_TX_C_DP<6>
  B37  PETP6  OUT  = P5E_CPU0_PE1_TX_C_DN<6>
  B38  GND_B38  POWER  = GND
  B39  PETN7  OUT  = P5E_CPU0_PE1_TX_C_DN<7>
  B40  PETP7  OUT  = P5E_CPU0_PE1_TX_C_DP<7>
  B41  GND_B41  POWER  = GND
  B42  \prsntb0#\  IN  = OCP_SFF_PRSNT0_R_N
  B43  GND_B43  POWER  = GND
  B44  PETN8  OUT  = P5E_CPU0_PE1_TX_C_DP<8>
  B45  PETP8  OUT  = P5E_CPU0_PE1_TX_C_DN<8>
  B46  GND_B46  POWER  = GND
  B47  PETN9  OUT  = P5E_CPU0_PE1_TX_C_DN<9>
  B48  PETP9  OUT  = P5E_CPU0_PE1_TX_C_DP<9>
  B49  GND_B49  POWER  = GND
  B50  PETN10  OUT  = P5E_CPU0_PE1_TX_C_DP<10>
  B51  PETP10  OUT  = P5E_CPU0_PE1_TX_C_DN<10>
  B52  GND_B52  POWER  = GND
  B53  PETN11  OUT  = P5E_CPU0_PE1_TX_C_DN<11>
  B54  PETP11  OUT  = P5E_CPU0_PE1_TX_C_DP<11>
  B55  GND_B55  POWER  = GND
  B56  PETN12  OUT  = P5E_CPU0_PE1_TX_C_DP<12>
  B57  PETP12  OUT  = P5E_CPU0_PE1_TX_C_DN<12>
  B58  GND_B58  POWER  = GND
  B59  PETN13  OUT  = P5E_CPU0_PE1_TX_C_DN<13>
  B60  PETP13  OUT  = P5E_CPU0_PE1_TX_C_DP<13>
  B61  GND_B61  POWER  = GND
  B62  PETN14  OUT  = P5E_CPU0_PE1_TX_C_DP<14>
  B63  PETP14  OUT  = P5E_CPU0_PE1_TX_C_DN<14>
  B64  GND_B64  POWER  = GND
  B65  PETN15  OUT  = P5E_CPU0_PE1_TX_C_DN<15>
  B66  PETP15  OUT  = P5E_CPU0_PE1_TX_C_DP<15>
  B67  GND_B67  POWER  = GND
  B68  RFU1_NC_B68  TRI  = TP_OCP_SFF_B68
  B69  RFU1_NC_B69  TRI  = TP_OCP_SFF_B69
  B70  \prsntb3#\  IN  = OCP_SFF_PRSNT3_R_N
  G1  G1  POWER  = GND
  G2  G2  POWER  = GND
  G3  G3  POWER  = GND
  G4  G4  POWER  = GND
  G5  G5  POWER  = GND
  OA1  \perst2#\  OUT  = RST_PERST2_OCP_SFF_N
  OA2  \perst3#\  OUT  = RST_PERST3_OCP_SFF_N
  OA3  \wake#\  IN  = IRQ_LVC3_OCP_SFF_WAKE_N
  OA4  RBT_ARB_IN  IN  = OCP_SFF_ISO1_RBT_ARB_IN
  OA5  RBT_ARB_OUT  OUT  = OCP_SFF_ISO2_RBT_ARB_OUT
  OA6  SLOT_ID1  OUT  = OCP_SFF_ID1
  OA7  RBT_TX_EN  OUT  = NCSI_OCP_SFF_TX_EN
  OA8  RBT_TXD1  OUT  = NCSI_OCP_SFF_TXD1
  OA9  RBT_TXD0  OUT  = NCSI_OCP_SFF_TXD0
  OA10  GND_OA10  POWER  = GND
  OA11  REFCLKN3  OUT  = CLK_100M_OCP_SFF_3_DN
  OA12  REFCLKP3  OUT  = CLK_100M_OCP_SFF_3_DP
  OA13  GND_OA13  POWER  = GND
  OA14  RBT_CLK_IN  OUT  = CLK_50M_NCSI_OCP_SFF_ISO
  OB1  NIC_PWR_GOOD  IN  = FM_OCP_SFF_PWR_GOOD
  OB2  MAIN_PWR_EN  OUT  = OCP_SFF_MAIN_PWR_EN_R
  OB3  \ld#\  OUT  = SGPIO_OCP_SFF_LD_N
  OB4  DATA_IN  IN  = SGPIO_OCP_SFF_DATAIN
  OB5  DATA_OUT  OUT  = SGPIO_OCP_SFF_DATAOUT
  OB6  CLK  OUT  = SGPIO_OCP_SFF_CLK
  OB7  SLOT_ID0  OUT  = OCP_SFF_ID0
  OB8  RBT_RXD1  IN  = NCSI_OCP_SFF_RXD1
  OB9  RBT_RXD0  IN  = NCSI_OCP_SFF_RXD0
  OB10  GND_OB10  POWER  = GND
  OB11  REFCLKN2  OUT  = CLK_100M_OCP_SFF_2_DN
  OB12  REFCLKP2  OUT  = CLK_100M_OCP_SFF_2_DP
  OB13  GND_OB13  POWER  = GND
  OB14  RBT_CRS_DV  OUT  = NCSI_OCP_SFF_CRS_DV
